(kicad_pcb
	(version 20260206)
	(generator "pcbnew")
	(generator_version "10.0")
	(general
		(thickness 1.6)
		(legacy_teardrops no)
	)
	(paper "A4")
	(title_block
		(title "Wiwynn_Tioga_Pass_MB.brd")
		(comment 1 "Tioga Pass / footprints 3579-3585 of 4770")
	)
	(layers
		(0 "F.Cu" signal "TOP")
		(4 "In1.Cu" signal "L2GND")
		(6 "In2.Cu" signal "L3")
		(8 "In3.Cu" signal "L4GND")
		(10 "In4.Cu" signal "L5")
		(12 "In5.Cu" signal "L6GND")
		(14 "In6.Cu" signal "L7VCC")
		(16 "In7.Cu" signal "L8VCC")
		(18 "In8.Cu" signal "L9GND")
		(20 "In9.Cu" signal "L10")
		(22 "In10.Cu" signal "L11GND")
		(24 "In11.Cu" signal "L12")
		(26 "In12.Cu" signal "L13GND")
		(2 "B.Cu" signal "BOTTOM")
		(9 "F.Adhes" user "F.Adhesive")
		(11 "B.Adhes" user "B.Adhesive")
		(13 "F.Paste" user "Package Geometry/Pastemask Top")
		(15 "B.Paste" user "Package Geometry/Pastemask Bottom")
		(5 "F.SilkS" user "Ref Des/Silkscreen Top")
		(7 "B.SilkS" user "Ref Des/Silkscreen Bottom")
		(1 "F.Mask" user "Board Geometry/Soldermask Top")
		(3 "B.Mask" user "Board Geometry/Soldermask Bottom")
		(17 "Dwgs.User" user "User.Drawings")
		(19 "Cmts.User" user "User.Comments")
		(21 "Eco1.User" user "User.Eco1")
		(23 "Eco2.User" user "User.Eco2")
		(25 "Edge.Cuts" user "Board Geometry/Outline")
		(27 "Margin" user)
		(31 "F.CrtYd" user "Package Geometry/Place Bound Top")
		(29 "B.CrtYd" user "Package Geometry/Place Bound Bottom")
		(35 "F.Fab" user "Ref Des/Assembly Top")
		(33 "B.Fab" user "Ref Des/Assembly Bottom")
	)
	(footprint ""
		(layer "B.Cu")
		(at 197.239128 -62.659006 90)
		(property "Reference" "R6R6"
			(at 0 0 90)
			(layer "B.SilkS")
			(hide yes)
			(effects
				(font
					(size 1.27 1.27)
				)
				(justify mirror)
			)
		)
		(property "Value" ""
			(at 0 0 90)
			(layer "B.Fab")
			(effects
				(font
					(size 1.27 1.27)
				)
				(justify mirror)
			)
		)
		(duplicate_pad_numbers_are_jumpers no)
		(fp_rect
			(start 0.2794 -0.1016)
			(end -0.2794 0.9906)
			(stroke
				(width 0)
				(type default)
			)
			(fill no)
			(layer "B.CrtYd")
		)
		(fp_line
			(start 0.2794 -0.1016)
			(end 0.2794 0.9906)
			(stroke
				(width 0.1)
				(type default)
			)
			(layer "B.Fab")
		)
		(fp_line
			(start -0.2794 -0.1016)
			(end 0.2794 -0.1016)
			(stroke
				(width 0.1)
				(type default)
			)
			(layer "B.Fab")
		)
		(fp_line
			(start 0.2794 0.9906)
			(end -0.2794 0.9906)
			(stroke
				(width 0.1)
				(type default)
			)
			(layer "B.Fab")
		)
		(fp_line
			(start -0.2794 0.9906)
			(end -0.2794 -0.1016)
			(stroke
				(width 0.1)
				(type default)
			)
			(layer "B.Fab")
		)
		(pad "1" smd rect
			(at 0 0 270)
			(size 0.508 0.508)
			(layers "B.Cu" "B.Mask" "B.Paste")
			(net "VR_PVCCIN_CPU0_PH2_VCIN")
		)
		(pad "2" smd rect
			(at 0 0.889 270)
			(size 0.508 0.508)
			(layers "B.Cu" "B.Mask" "B.Paste")
			(net "P5V_STBY")
		)
		(zone
			(layer "B.Cu")
			(hatch none 0.5)
			(connect_pads
				(clearance 0)
			)
			(min_thickness 0.25)
			(keepout
				(tracks allowed)
				(vias not_allowed)
				(pads allowed)
				(copperpour not_allowed)
				(footprints allowed)
			)
			(placement
				(enabled no)
				(sheetname "")
			)
			(fill
				(thermal_gap 0.5)
				(thermal_bridge_width 0.5)
				(island_removal_mode 0)
			)
			(polygon
				(pts
					(xy 197.493128 -62.913006) (xy 197.493128 -62.405006) (xy 197.874128 -62.405006) (xy 197.874128 -62.913006)
				)
			)
		)
		(zone
			(layer "B.Cu")
			(hatch none 0.5)
			(connect_pads
				(clearance 0)
			)
			(min_thickness 0.25)
			(keepout
				(tracks not_allowed)
				(vias allowed)
				(pads allowed)
				(copperpour not_allowed)
				(footprints allowed)
			)
			(placement
				(enabled no)
				(sheetname "")
			)
			(fill
				(thermal_gap 0.5)
				(thermal_bridge_width 0.5)
				(island_removal_mode 0)
			)
			(polygon
				(pts
					(xy 197.493128 -62.913006) (xy 197.493128 -62.405006) (xy 197.874128 -62.405006) (xy 197.874128 -62.913006)
				)
			)
		)
	)
	(footprint ""
		(layer "B.Cu")
		(at 375.285 -138.1125)
		(property "Reference" "C3L22"
			(at 0 0 0)
			(layer "B.SilkS")
			(hide yes)
			(effects
				(font
					(size 1.27 1.27)
				)
				(justify mirror)
			)
		)
		(property "Value" ""
			(at 0 0 0)
			(layer "B.Fab")
			(effects
				(font
					(size 1.27 1.27)
				)
				(justify mirror)
			)
		)
		(duplicate_pad_numbers_are_jumpers no)
		(fp_poly
			(pts
				(xy 0.4953 -0.2032) (xy -0.4953 -0.2032) (xy -0.4953 1.6002) (xy 0.4953 1.6002)
			)
			(stroke
				(width 0)
				(type default)
			)
			(fill no)
			(layer "B.CrtYd")
		)
		(fp_line
			(start -0.4953 -0.2032)
			(end -0.4953 1.6002)
			(stroke
				(width 0.1)
				(type default)
			)
			(layer "B.Fab")
		)
		(fp_line
			(start -0.4953 1.6002)
			(end 0.4953 1.6002)
			(stroke
				(width 0.1)
				(type default)
			)
			(layer "B.Fab")
		)
		(fp_line
			(start 0.4953 -0.2032)
			(end -0.4953 -0.2032)
			(stroke
				(width 0.1)
				(type default)
			)
			(layer "B.Fab")
		)
		(fp_line
			(start 0.4953 1.6002)
			(end 0.4953 -0.2032)
			(stroke
				(width 0.1)
				(type default)
			)
			(layer "B.Fab")
		)
		(pad "1" smd rect
			(at 0 0 180)
			(size 0.762 0.889)
			(layers "B.Cu" "B.Mask" "B.Paste")
			(net "PVNN_PCH_STBY")
		)
		(pad "2" smd rect
			(at 0 1.397 180)
			(size 0.762 0.889)
			(layers "B.Cu" "B.Mask" "B.Paste")
			(net "GND")
		)
		(zone
			(layer "B.Cu")
			(hatch none 0.5)
			(connect_pads
				(clearance 0)
			)
			(min_thickness 0.25)
			(keepout
				(tracks not_allowed)
				(vias allowed)
				(pads allowed)
				(copperpour not_allowed)
				(footprints allowed)
			)
			(placement
				(enabled no)
				(sheetname "")
			)
			(fill
				(thermal_gap 0.5)
				(thermal_bridge_width 0.5)
				(island_removal_mode 0)
			)
			(polygon
				(pts
					(xy 375.666 -137.668) (xy 374.904 -137.668) (xy 374.904 -137.16) (xy 375.666 -137.16)
				)
			)
		)
	)
	(footprint ""
		(layer "B.Cu")
		(at 179.206144 -68.341494 -90)
		(property "Reference" "R6P37"
			(at 0 0 90)
			(layer "B.SilkS")
			(hide yes)
			(effects
				(font
					(size 1.27 1.27)
				)
				(justify mirror)
			)
		)
		(property "Value" ""
			(at 0 0 90)
			(layer "B.Fab")
			(effects
				(font
					(size 1.27 1.27)
				)
				(justify mirror)
			)
		)
		(duplicate_pad_numbers_are_jumpers no)
		(fp_rect
			(start -0.2794 -0.1016)
			(end 0.2794 0.9906)
			(stroke
				(width 0)
				(type default)
			)
			(fill no)
			(layer "B.CrtYd")
		)
		(fp_line
			(start -0.2794 0.9906)
			(end -0.2794 -0.1016)
			(stroke
				(width 0.1)
				(type default)
			)
			(layer "B.Fab")
		)
		(fp_line
			(start 0.2794 0.9906)
			(end -0.2794 0.9906)
			(stroke
				(width 0.1)
				(type default)
			)
			(layer "B.Fab")
		)
		(fp_line
			(start -0.2794 -0.1016)
			(end 0.2794 -0.1016)
			(stroke
				(width 0.1)
				(type default)
			)
			(layer "B.Fab")
		)
		(fp_line
			(start 0.2794 -0.1016)
			(end 0.2794 0.9906)
			(stroke
				(width 0.1)
				(type default)
			)
			(layer "B.Fab")
		)
		(pad "1" smd rect
			(at 0 0 90)
			(size 0.508 0.508)
			(layers "B.Cu" "B.Mask" "B.Paste")
			(net "P3V3_STBY")
		)
		(pad "2" smd rect
			(at 0 0.889 90)
			(size 0.508 0.508)
			(layers "B.Cu" "B.Mask" "B.Paste")
			(net "SMB_VR_STBY_LVC3_SCL")
		)
		(zone
			(layer "B.Cu")
			(hatch none 0.5)
			(connect_pads
				(clearance 0)
			)
			(min_thickness 0.25)
			(keepout
				(tracks not_allowed)
				(vias allowed)
				(pads allowed)
				(copperpour not_allowed)
				(footprints allowed)
			)
			(placement
				(enabled no)
				(sheetname "")
			)
			(fill
				(thermal_gap 0.5)
				(thermal_bridge_width 0.5)
				(island_removal_mode 0)
			)
			(polygon
				(pts
					(xy 178.952144 -68.595494) (xy 178.571144 -68.595494) (xy 178.571144 -68.087494) (xy 178.952144 -68.087494)
				)
			)
		)
		(zone
			(layer "B.Cu")
			(hatch none 0.5)
			(connect_pads
				(clearance 0)
			)
			(min_thickness 0.25)
			(keepout
				(tracks allowed)
				(vias not_allowed)
				(pads allowed)
				(copperpour not_allowed)
				(footprints allowed)
			)
			(placement
				(enabled no)
				(sheetname "")
			)
			(fill
				(thermal_gap 0.5)
				(thermal_bridge_width 0.5)
				(island_removal_mode 0)
			)
			(polygon
				(pts
					(xy 178.952144 -68.595494) (xy 178.571144 -68.595494) (xy 178.571144 -68.087494) (xy 178.952144 -68.087494)
				)
			)
		)
	)
	(footprint ""
		(layer "B.Cu")
		(at 366.522 -62.2935 180)
		(property "Reference" "R3P46"
			(at 0 0 0)
			(layer "B.SilkS")
			(hide yes)
			(effects
				(font
					(size 1.27 1.27)
				)
				(justify mirror)
			)
		)
		(property "Value" ""
			(at 0 0 0)
			(layer "B.Fab")
			(effects
				(font
					(size 1.27 1.27)
				)
				(justify mirror)
			)
		)
		(duplicate_pad_numbers_are_jumpers no)
		(fp_poly
			(pts
				(xy 0.2794 -0.1016) (xy -0.2794 -0.1016) (xy -0.2794 0.9906) (xy 0.2794 0.9906)
			)
			(stroke
				(width 0)
				(type default)
			)
			(fill no)
			(layer "B.CrtYd")
		)
		(fp_line
			(start 0.2794 0.9906)
			(end -0.2794 0.9906)
			(stroke
				(width 0.1)
				(type default)
			)
			(layer "B.Fab")
		)
		(fp_line
			(start 0.2794 -0.1016)
			(end 0.2794 0.9906)
			(stroke
				(width 0.1)
				(type default)
			)
			(layer "B.Fab")
		)
		(fp_line
			(start -0.2794 0.9906)
			(end -0.2794 -0.1016)
			(stroke
				(width 0.1)
				(type default)
			)
			(layer "B.Fab")
		)
		(fp_line
			(start -0.2794 -0.1016)
			(end 0.2794 -0.1016)
			(stroke
				(width 0.1)
				(type default)
			)
			(layer "B.Fab")
		)
		(pad "1" smd rect
			(at 0 0)
			(size 0.508 0.508)
			(layers "B.Cu" "B.Mask" "B.Paste")
			(net "FM_CPU1_FIVR_FAULT_R_LVT3")
		)
		(pad "2" smd rect
			(at 0 0.889)
			(size 0.508 0.508)
			(layers "B.Cu" "B.Mask" "B.Paste")
			(net "FM_CPU1_FIVR_FAULT_LVT3")
		)
		(zone
			(layer "B.Cu")
			(hatch none 0.5)
			(connect_pads
				(clearance 0)
			)
			(min_thickness 0.25)
			(keepout
				(tracks not_allowed)
				(vias allowed)
				(pads allowed)
				(copperpour not_allowed)
				(footprints allowed)
			)
			(placement
				(enabled no)
				(sheetname "")
			)
			(fill
				(thermal_gap 0.5)
				(thermal_bridge_width 0.5)
				(island_removal_mode 0)
			)
			(polygon
				(pts
					(xy 366.268 -62.9285) (xy 366.776 -62.9285) (xy 366.776 -62.5475) (xy 366.268 -62.5475)
				)
			)
		)
		(zone
			(layer "B.Cu")
			(hatch none 0.5)
			(connect_pads
				(clearance 0)
			)
			(min_thickness 0.25)
			(keepout
				(tracks allowed)
				(vias not_allowed)
				(pads allowed)
				(copperpour not_allowed)
				(footprints allowed)
			)
			(placement
				(enabled no)
				(sheetname "")
			)
			(fill
				(thermal_gap 0.5)
				(thermal_bridge_width 0.5)
				(island_removal_mode 0)
			)
			(polygon
				(pts
					(xy 366.268 -62.5475) (xy 366.776 -62.5475) (xy 366.776 -62.9285) (xy 366.268 -62.9285)
				)
			)
		)
	)
	(footprint ""
		(layer "B.Cu")
		(at 376.215656 -92.173298)
		(property "Reference" "R1W27"
			(at 0.8382 -0.67818 0)
			(unlocked yes)
			(layer "B.SilkS")
			(effects
				(font
					(size 0.4064 0.254)
					(thickness 0.1524)
				)
				(justify left mirror)
			)
		)
		(property "Value" ""
			(at 0 0 0)
			(layer "B.Fab")
			(effects
				(font
					(size 1.27 1.27)
				)
				(justify mirror)
			)
		)
		(duplicate_pad_numbers_are_jumpers no)
		(fp_poly
			(pts
				(xy 0.2794 -0.1016) (xy -0.2794 -0.1016) (xy -0.2794 0.9906) (xy 0.2794 0.9906)
			)
			(stroke
				(width 0)
				(type default)
			)
			(fill no)
			(layer "B.CrtYd")
		)
		(fp_line
			(start -0.2794 -0.1016)
			(end 0.2794 -0.1016)
			(stroke
				(width 0.1)
				(type default)
			)
			(layer "B.Fab")
		)
		(fp_line
			(start -0.2794 0.9906)
			(end -0.2794 -0.1016)
			(stroke
				(width 0.1)
				(type default)
			)
			(layer "B.Fab")
		)
		(fp_line
			(start 0.2794 -0.1016)
			(end 0.2794 0.9906)
			(stroke
				(width 0.1)
				(type default)
			)
			(layer "B.Fab")
		)
		(fp_line
			(start 0.2794 0.9906)
			(end -0.2794 0.9906)
			(stroke
				(width 0.1)
				(type default)
			)
			(layer "B.Fab")
		)
		(pad "1" smd rect
			(at 0 0 180)
			(size 0.508 0.508)
			(layers "B.Cu" "B.Mask" "B.Paste")
			(net "FM_PWR_BTN_N")
		)
		(pad "2" smd rect
			(at 0 0.889 180)
			(size 0.508 0.508)
			(layers "B.Cu" "B.Mask" "B.Paste")
			(net "FM_PWR_BTN_R2_N")
		)
		(zone
			(layer "B.Cu")
			(hatch none 0.5)
			(connect_pads
				(clearance 0)
			)
			(min_thickness 0.25)
			(keepout
				(tracks allowed)
				(vias not_allowed)
				(pads allowed)
				(copperpour not_allowed)
				(footprints allowed)
			)
			(placement
				(enabled no)
				(sheetname "")
			)
			(fill
				(thermal_gap 0.5)
				(thermal_bridge_width 0.5)
				(island_removal_mode 0)
			)
			(polygon
				(pts
					(xy 376.469656 -91.919298) (xy 375.961656 -91.919298) (xy 375.961656 -91.538298) (xy 376.469656 -91.538298)
				)
			)
		)
		(zone
			(layer "B.Cu")
			(hatch none 0.5)
			(connect_pads
				(clearance 0)
			)
			(min_thickness 0.25)
			(keepout
				(tracks not_allowed)
				(vias allowed)
				(pads allowed)
				(copperpour not_allowed)
				(footprints allowed)
			)
			(placement
				(enabled no)
				(sheetname "")
			)
			(fill
				(thermal_gap 0.5)
				(thermal_bridge_width 0.5)
				(island_removal_mode 0)
			)
			(polygon
				(pts
					(xy 376.469656 -91.538298) (xy 375.961656 -91.538298) (xy 375.961656 -91.919298) (xy 376.469656 -91.919298)
				)
			)
		)
	)
	(footprint ""
		(layer "B.Cu")
		(at 368.7064 -141.0462 180)
		(property "Reference" "C3L18"
			(at -3.10007 3.24612 270)
			(unlocked yes)
			(layer "B.SilkS")
			(effects
				(font
					(size 0.7874 0.5842)
					(thickness 0.1524)
				)
				(justify mirror)
			)
		)
		(property "Value" ""
			(at 0 0 0)
			(layer "B.Fab")
			(effects
				(font
					(size 1.27 1.27)
				)
				(justify mirror)
			)
		)
		(duplicate_pad_numbers_are_jumpers no)
		(fp_line
			(start 2.563114 1.633728)
			(end 1.6002 1.633728)
			(stroke
				(width 0.1524)
				(type default)
			)
			(layer "B.SilkS")
		)
		(fp_line
			(start 2.563114 -1.616456)
			(end 2.563114 1.633728)
			(stroke
				(width 0.1524)
				(type default)
			)
			(layer "B.SilkS")
		)
		(fp_line
			(start 2.286 7.366)
			(end 2.286 1.632712)
			(stroke
				(width 0.1524)
				(type default)
			)
			(layer "B.SilkS")
		)
		(fp_line
			(start 2.286 7.366)
			(end 1.60147 7.366)
			(stroke
				(width 0.1524)
				(type default)
			)
			(layer "B.SilkS")
		)
		(fp_line
			(start 1.6002 -1.616456)
			(end 2.563114 -1.616456)
			(stroke
				(width 0.1524)
				(type default)
			)
			(layer "B.SilkS")
		)
		(fp_line
			(start -1.6002 -1.616456)
			(end -2.504948 -1.616456)
			(stroke
				(width 0.1524)
				(type default)
			)
			(layer "B.SilkS")
		)
		(fp_line
			(start -2.286 7.366)
			(end -1.600708 7.366)
			(stroke
				(width 0.1524)
				(type default)
			)
			(layer "B.SilkS")
		)
		(fp_line
			(start -2.286 7.366)
			(end -2.286 1.63195)
			(stroke
				(width 0.1524)
				(type default)
			)
			(layer "B.SilkS")
		)
		(fp_line
			(start -2.504948 1.633728)
			(end -1.6002 1.633728)
			(stroke
				(width 0.1524)
				(type default)
			)
			(layer "B.SilkS")
		)
		(fp_line
			(start -2.504948 -1.616456)
			(end -2.504948 1.633728)
			(stroke
				(width 0.1524)
				(type default)
			)
			(layer "B.SilkS")
		)
		(fp_rect
			(start 2.286 7.366)
			(end -2.286 -0.254)
			(stroke
				(width 0)
				(type default)
			)
			(fill no)
			(layer "B.CrtYd")
		)
		(fp_line
			(start 2.286 7.366)
			(end 2.286 -0.254)
			(stroke
				(width 0.1)
				(type default)
			)
			(layer "B.Fab")
		)
		(fp_line
			(start 2.286 -0.254)
			(end -2.286 -0.254)
			(stroke
				(width 0.1)
				(type default)
			)
			(layer "B.Fab")
		)
		(fp_line
			(start -2.286 7.366)
			(end 2.286 7.366)
			(stroke
				(width 0.1)
				(type default)
			)
			(layer "B.Fab")
		)
		(fp_line
			(start -2.286 -0.254)
			(end -2.286 7.366)
			(stroke
				(width 0.1)
				(type default)
			)
			(layer "B.Fab")
		)
		(pad "1" smd rect
			(at 0 0)
			(size 2.54 3.048)
			(layers "B.Cu" "B.Mask" "B.Paste")
			(net "PVNN_PCH_STBY")
		)
		(pad "2" smd rect
			(at 0 7.112)
			(size 2.54 3.048)
			(layers "B.Cu" "B.Mask" "B.Paste")
			(net "GND")
		)
	)
	(footprint ""
		(layer "B.Cu")
		(at 404.43658 -143.561816 -90)
		(property "Reference" "C2L32"
			(at 0 0 90)
			(layer "B.SilkS")
			(hide yes)
			(effects
				(font
					(size 1.27 1.27)
				)
				(justify mirror)
			)
		)
		(property "Value" ""
			(at 0 0 90)
			(layer "B.Fab")
			(effects
				(font
					(size 1.27 1.27)
				)
				(justify mirror)
			)
		)
		(duplicate_pad_numbers_are_jumpers no)
		(fp_poly
			(pts
				(xy 0.7239 -0.2159) (xy -0.7239 -0.2159) (xy -0.7239 1.9939) (xy 0.7239 1.9939)
			)
			(stroke
				(width 0)
				(type default)
			)
			(fill no)
			(layer "B.CrtYd")
		)
		(fp_line
			(start -0.7239 1.9939)
			(end -0.7239 -0.2159)
			(stroke
				(width 0.1)
				(type default)
			)
			(layer "B.Fab")
		)
		(fp_line
			(start 0.7239 1.9939)
			(end -0.7239 1.9939)
			(stroke
				(width 0.1)
				(type default)
			)
			(layer "B.Fab")
		)
		(fp_line
			(start -0.7239 -0.2159)
			(end 0.7239 -0.2159)
			(stroke
				(width 0.1)
				(type default)
			)
			(layer "B.Fab")
		)
		(fp_line
			(start 0.7239 -0.2159)
			(end 0.7239 1.9939)
			(stroke
				(width 0.1)
				(type default)
			)
			(layer "B.Fab")
		)
		(pad "1" smd rect
			(at 0 0 90)
			(size 1.27 1.016)
			(layers "B.Cu" "B.Mask" "B.Paste")
			(net "P1V8_PCH_STBY")
		)
		(pad "2" smd rect
			(at 0 1.778 90)
			(size 1.27 1.016)
			(layers "B.Cu" "B.Mask" "B.Paste")
			(net "GND")
		)
		(zone
			(layer "B.Cu")
			(hatch none 0.5)
			(connect_pads
				(clearance 0)
			)
			(min_thickness 0.25)
			(keepout
				(tracks not_allowed)
				(vias allowed)
				(pads allowed)
				(copperpour not_allowed)
				(footprints allowed)
			)
			(placement
				(enabled no)
				(sheetname "")
			)
			(fill
				(thermal_gap 0.5)
				(thermal_bridge_width 0.5)
				(island_removal_mode 0)
			)
			(polygon
				(pts
					(xy 403.92858 -142.926816) (xy 403.92858 -144.196816) (xy 403.16658 -144.196816) (xy 403.16658 -142.926816)
				)
			)
		)
	)
)
